(kicad_pcb
	(version 20260206)
	(generator "pcbnew")
	(generator_version "10.0")
	(general
		(thickness 1.6)
		(legacy_teardrops no)
	)
	(paper "A4")
	(title_block
		(title "peb — Lightning_PEB_BRD.brd")
		(comment 1 "Lightning (Wiwynn / Facebook NVMe JBOF) / footprints 1020-1027 of 2563")
	)
	(layers
		(0 "F.Cu" signal "TOP")
		(4 "In1.Cu" signal "L2GND")
		(6 "In2.Cu" signal "L3")
		(8 "In3.Cu" signal "L4VCC")
		(10 "In4.Cu" signal "L5VCC")
		(12 "In5.Cu" signal "L6")
		(14 "In6.Cu" signal "L7GND")
		(2 "B.Cu" signal "BOTTOM")
		(9 "F.Adhes" user "F.Adhesive")
		(11 "B.Adhes" user "B.Adhesive")
		(13 "F.Paste" user "Package Geometry/Pastemask Top")
		(15 "B.Paste" user "Package Geometry/Pastemask Bottom")
		(5 "F.SilkS" user "Ref Des/Silkscreen Top")
		(7 "B.SilkS" user "Ref Des/Silkscreen Bottom")
		(1 "F.Mask" user "Board Geometry/Soldermask Top")
		(3 "B.Mask" user "Board Geometry/Soldermask Bottom")
		(17 "Dwgs.User" user "User.Drawings")
		(19 "Cmts.User" user "User.Comments")
		(21 "Eco1.User" user "User.Eco1")
		(23 "Eco2.User" user "User.Eco2")
		(25 "Edge.Cuts" user "Board Geometry/Outline")
		(27 "Margin" user)
		(31 "F.CrtYd" user "Package Geometry/Place Bound Top")
		(29 "B.CrtYd" user "Package Geometry/Place Bound Bottom")
		(35 "F.Fab" user "Ref Des/Assembly Top")
		(33 "B.Fab" user "Ref Des/Assembly Bottom")
	)
	(footprint ""
		(layer "F.Cu")
		(at 304.673 -33.528)
		(property "Reference" "C26"
			(at 0 0 0)
			(layer "F.SilkS")
			(hide yes)
			(effects
				(font
					(size 1.27 1.27)
				)
			)
		)
		(property "Value" "SCD22U10V2KX-1GP"
			(at 1.1811 -2.7051 0)
			(unlocked yes)
			(layer "F.Fab")
			(hide yes)
			(effects
				(font
					(size 1.016 1.016)
					(thickness 0.1524)
				)
			)
		)
		(property "Device Type" "C402H22"
			(at 1.1811 -4.2291 0)
			(unlocked yes)
			(layer "F.Fab")
			(hide yes)
			(effects
				(font
					(size 1.016 1.016)
					(thickness 0.1524)
				)
			)
		)
		(duplicate_pad_numbers_are_jumpers no)
		(fp_rect
			(start -0.4318 0.9525)
			(end 0.4318 -0.9525)
			(stroke
				(width 0)
				(type default)
			)
			(fill no)
			(layer "F.CrtYd")
		)
		(fp_rect
			(start -0.4318 0.9525)
			(end 0.4318 -0.9525)
			(stroke
				(width 0)
				(type default)
			)
			(fill no)
			(layer "F.Fab")
		)
		(pad "1" smd custom
			(at 0 -0.4445)
			(size 0.1524 0.1524)
			(layers "F.Cu" "F.Mask" "F.Paste")
			(net "PCIE_TX_CAP_N7")
			(options
				(clearance outline)
				(anchor circle)
			)
			(primitives
				(gr_poly
					(pts
						(arc
							(start 0.3048 -0.2032)
							(mid 0.275042 -0.275042)
							(end 0.2032 -0.3048)
						)
						(arc
							(start -0.2032 -0.3048)
							(mid -0.275042 -0.275042)
							(end -0.3048 -0.2032)
						)
						(arc
							(start -0.3048 0.2032)
							(mid -0.275042 0.275042)
							(end -0.2032 0.3048)
						)
						(arc
							(start 0.2032 0.3048)
							(mid 0.275042 0.275042)
							(end 0.3048 0.2032)
						)
					)
					(width 0)
					(fill yes)
				)
			)
		)
		(pad "2" smd custom
			(at 0 0.4445)
			(size 0.1524 0.1524)
			(layers "F.Cu" "F.Mask" "F.Paste")
			(net "PCIE_TX_N7")
			(options
				(clearance outline)
				(anchor circle)
			)
			(primitives
				(gr_poly
					(pts
						(arc
							(start 0.3048 -0.2032)
							(mid 0.275042 -0.275042)
							(end 0.2032 -0.3048)
						)
						(arc
							(start -0.2032 -0.3048)
							(mid -0.275042 -0.275042)
							(end -0.3048 -0.2032)
						)
						(arc
							(start -0.3048 0.2032)
							(mid -0.275042 0.275042)
							(end -0.2032 0.3048)
						)
						(arc
							(start 0.2032 0.3048)
							(mid 0.275042 0.275042)
							(end 0.3048 0.2032)
						)
					)
					(width 0)
					(fill yes)
				)
			)
		)
	)
	(footprint ""
		(layer "F.Cu")
		(at 14.097 -196.9262 -90)
		(property "Reference" "C7278"
			(at 0 0 270)
			(layer "F.SilkS")
			(hide yes)
			(effects
				(font
					(size 1.27 1.27)
				)
			)
		)
		(property "Value" "SCD1U25V3JX-GP"
			(at 0 -2.8194 270)
			(unlocked yes)
			(layer "F.Fab")
			(hide yes)
			(effects
				(font
					(size 1.016 1.016)
					(thickness 0.1524)
				)
			)
		)
		(property "Device Type" "C603H36"
			(at 0 -4.3434 270)
			(unlocked yes)
			(layer "F.Fab")
			(hide yes)
			(effects
				(font
					(size 1.016 1.016)
					(thickness 0.1524)
				)
			)
		)
		(duplicate_pad_numbers_are_jumpers no)
		(fp_line
			(start 0.508 0)
			(end -0.508 0)
			(stroke
				(width 0.2032)
				(type default)
			)
			(layer "F.SilkS")
		)
		(fp_rect
			(start -0.5842 1.3335)
			(end 0.5842 -1.3335)
			(stroke
				(width 0)
				(type default)
			)
			(fill no)
			(layer "F.CrtYd")
		)
		(fp_rect
			(start -0.5842 1.3335)
			(end 0.5842 -1.3335)
			(stroke
				(width 0)
				(type default)
			)
			(fill no)
			(layer "F.Fab")
		)
		(pad "1" smd custom
			(at 0 -0.762 270)
			(size 0.2159 0.2159)
			(layers "F.Cu" "F.Mask" "F.Paste")
			(net "MB0_ISET_R")
			(options
				(clearance outline)
				(anchor circle)
			)
			(primitives
				(gr_poly
					(pts
						(arc
							(start -0.3302 -0.4318)
							(mid -0.402042 -0.402042)
							(end -0.4318 -0.3302)
						)
						(arc
							(start -0.4318 0.3302)
							(mid -0.402042 0.402042)
							(end -0.3302 0.4318)
						)
						(arc
							(start 0.3302 0.4318)
							(mid 0.402042 0.402042)
							(end 0.4318 0.3302)
						)
						(arc
							(start 0.4318 -0.3302)
							(mid 0.402042 -0.402042)
							(end 0.3302 -0.4318)
						)
					)
					(width 0)
					(fill yes)
				)
			)
		)
		(pad "2" smd custom
			(at 0 0.762 270)
			(size 0.2159 0.2159)
			(layers "F.Cu" "F.Mask" "F.Paste")
			(net "AGND_CURRENT_MON")
			(options
				(clearance outline)
				(anchor circle)
			)
			(primitives
				(gr_poly
					(pts
						(arc
							(start -0.3302 -0.4318)
							(mid -0.402042 -0.402042)
							(end -0.4318 -0.3302)
						)
						(arc
							(start -0.4318 0.3302)
							(mid -0.402042 0.402042)
							(end -0.3302 0.4318)
						)
						(arc
							(start 0.3302 0.4318)
							(mid 0.402042 0.402042)
							(end 0.4318 0.3302)
						)
						(arc
							(start 0.4318 -0.3302)
							(mid 0.402042 -0.402042)
							(end 0.3302 -0.4318)
						)
					)
					(width 0)
					(fill yes)
				)
			)
		)
	)
	(footprint ""
		(layer "F.Cu")
		(at 120.1928 -98.7552 -90)
		(property "Reference" "C248"
			(at 0 0 270)
			(layer "F.SilkS")
			(hide yes)
			(effects
				(font
					(size 1.27 1.27)
				)
			)
		)
		(property "Value" "SC220P50V3JN-GP"
			(at 0 -2.8194 270)
			(unlocked yes)
			(layer "F.Fab")
			(hide yes)
			(effects
				(font
					(size 1.016 1.016)
					(thickness 0.1524)
				)
			)
		)
		(property "Device Type" "C603H36"
			(at 0 -4.3434 270)
			(unlocked yes)
			(layer "F.Fab")
			(hide yes)
			(effects
				(font
					(size 1.016 1.016)
					(thickness 0.1524)
				)
			)
		)
		(duplicate_pad_numbers_are_jumpers no)
		(fp_line
			(start 0.508 0)
			(end -0.508 0)
			(stroke
				(width 0.2032)
				(type default)
			)
			(layer "F.SilkS")
		)
		(fp_rect
			(start -0.5842 1.3335)
			(end 0.5842 -1.3335)
			(stroke
				(width 0)
				(type default)
			)
			(fill no)
			(layer "F.CrtYd")
		)
		(fp_rect
			(start -0.5842 1.3335)
			(end 0.5842 -1.3335)
			(stroke
				(width 0)
				(type default)
			)
			(fill no)
			(layer "F.Fab")
		)
		(pad "1" smd custom
			(at 0 -0.762 270)
			(size 0.2159 0.2159)
			(layers "F.Cu" "F.Mask" "F.Paste")
			(net "BUF_I2C_SDA_2_R")
			(options
				(clearance outline)
				(anchor circle)
			)
			(primitives
				(gr_poly
					(pts
						(arc
							(start -0.3302 -0.4318)
							(mid -0.402042 -0.402042)
							(end -0.4318 -0.3302)
						)
						(arc
							(start -0.4318 0.3302)
							(mid -0.402042 0.402042)
							(end -0.3302 0.4318)
						)
						(arc
							(start 0.3302 0.4318)
							(mid 0.402042 0.402042)
							(end 0.4318 0.3302)
						)
						(arc
							(start 0.4318 -0.3302)
							(mid 0.402042 -0.402042)
							(end 0.3302 -0.4318)
						)
					)
					(width 0)
					(fill yes)
				)
			)
		)
		(pad "2" smd custom
			(at 0 0.762 270)
			(size 0.2159 0.2159)
			(layers "F.Cu" "F.Mask" "F.Paste")
			(net "GND")
			(options
				(clearance outline)
				(anchor circle)
			)
			(primitives
				(gr_poly
					(pts
						(arc
							(start -0.3302 -0.4318)
							(mid -0.402042 -0.402042)
							(end -0.4318 -0.3302)
						)
						(arc
							(start -0.4318 0.3302)
							(mid -0.402042 0.402042)
							(end -0.3302 0.4318)
						)
						(arc
							(start 0.3302 0.4318)
							(mid 0.402042 0.402042)
							(end 0.4318 0.3302)
						)
						(arc
							(start 0.4318 -0.3302)
							(mid 0.402042 -0.402042)
							(end 0.3302 -0.4318)
						)
					)
					(width 0)
					(fill yes)
				)
			)
		)
	)
	(footprint ""
		(layer "F.Cu")
		(at 24.765 -160.909)
		(property "Reference" "R504"
			(at 0 0 0)
			(layer "F.SilkS")
			(hide yes)
			(effects
				(font
					(size 1.27 1.27)
				)
			)
		)
		(property "Value" "0R2J-2-GP"
			(at 0.064008 -3.993896 0)
			(unlocked yes)
			(layer "F.Fab")
			(hide yes)
			(effects
				(font
					(size 1.016 1.016)
					(thickness 0.1524)
				)
			)
		)
		(property "Device Type" "R402H16"
			(at 0.064008 -5.517896 0)
			(unlocked yes)
			(layer "F.Fab")
			(hide yes)
			(effects
				(font
					(size 1.016 1.016)
					(thickness 0.1524)
				)
			)
		)
		(duplicate_pad_numbers_are_jumpers no)
		(fp_line
			(start -0.508 -0.9398)
			(end -0.508 0.9398)
			(stroke
				(width 0.1524)
				(type default)
			)
			(layer "F.SilkS")
		)
		(fp_line
			(start 0.508 -0.9398)
			(end -0.508 -0.9398)
			(stroke
				(width 0.1524)
				(type default)
			)
			(layer "F.SilkS")
		)
		(fp_rect
			(start -0.508 0.9398)
			(end 0.508 -0.9398)
			(stroke
				(width 0)
				(type default)
			)
			(fill no)
			(layer "F.CrtYd")
		)
		(fp_rect
			(start -0.508 0.9398)
			(end 0.508 -0.9398)
			(stroke
				(width 0)
				(type default)
			)
			(fill no)
			(layer "F.Fab")
		)
		(pad "1" smd custom
			(at 0 -0.4445)
			(size 0.1397 0.1397)
			(layers "F.Cu" "F.Mask" "F.Paste")
			(net "BMC_RESET#_DDR3_BUF")
			(options
				(clearance outline)
				(anchor circle)
			)
			(primitives
				(gr_poly
					(pts
						(arc
							(start -0.1778 -0.2794)
							(mid -0.249642 -0.249642)
							(end -0.2794 -0.1778)
						)
						(arc
							(start -0.2794 0.1778)
							(mid -0.249642 0.249642)
							(end -0.1778 0.2794)
						)
						(arc
							(start 0.1778 0.2794)
							(mid 0.249642 0.249642)
							(end 0.2794 0.1778)
						)
						(arc
							(start 0.2794 -0.1778)
							(mid 0.249642 -0.249642)
							(end 0.1778 -0.2794)
						)
					)
					(width 0)
					(fill yes)
				)
			)
		)
		(pad "2" smd custom
			(at 0 0.4445)
			(size 0.1397 0.1397)
			(layers "F.Cu" "F.Mask" "F.Paste")
			(net "BMC_DDR3_RST_N")
			(options
				(clearance outline)
				(anchor circle)
			)
			(primitives
				(gr_poly
					(pts
						(arc
							(start -0.1778 -0.2794)
							(mid -0.249642 -0.249642)
							(end -0.2794 -0.1778)
						)
						(arc
							(start -0.2794 0.1778)
							(mid -0.249642 0.249642)
							(end -0.1778 0.2794)
						)
						(arc
							(start 0.1778 0.2794)
							(mid 0.249642 0.249642)
							(end 0.2794 0.1778)
						)
						(arc
							(start 0.2794 -0.1778)
							(mid 0.249642 -0.249642)
							(end 0.1778 -0.2794)
						)
					)
					(width 0)
					(fill yes)
				)
			)
		)
	)
	(footprint ""
		(layer "F.Cu")
		(at 56.261 -118.11 90)
		(property "Reference" "R581"
			(at 0 0 90)
			(layer "F.SilkS")
			(hide yes)
			(effects
				(font
					(size 1.27 1.27)
				)
			)
		)
		(property "Value" "4K7R2F-GP"
			(at 0.064008 -3.993896 90)
			(unlocked yes)
			(layer "F.Fab")
			(hide yes)
			(effects
				(font
					(size 1.016 1.016)
					(thickness 0.1524)
				)
			)
		)
		(property "Device Type" "R402H16"
			(at 0.064008 -5.517896 90)
			(unlocked yes)
			(layer "F.Fab")
			(hide yes)
			(effects
				(font
					(size 1.016 1.016)
					(thickness 0.1524)
				)
			)
		)
		(duplicate_pad_numbers_are_jumpers no)
		(fp_line
			(start 0.508 -0.9398)
			(end -0.508 -0.9398)
			(stroke
				(width 0.1524)
				(type default)
			)
			(layer "F.SilkS")
		)
		(fp_line
			(start -0.508 -0.9398)
			(end -0.508 0.9398)
			(stroke
				(width 0.1524)
				(type default)
			)
			(layer "F.SilkS")
		)
		(fp_rect
			(start -0.508 0.9398)
			(end 0.508 -0.9398)
			(stroke
				(width 0)
				(type default)
			)
			(fill no)
			(layer "F.CrtYd")
		)
		(fp_rect
			(start -0.508 0.9398)
			(end 0.508 -0.9398)
			(stroke
				(width 0)
				(type default)
			)
			(fill no)
			(layer "F.Fab")
		)
		(pad "1" smd custom
			(at 0 -0.4445 90)
			(size 0.1397 0.1397)
			(layers "F.Cu" "F.Mask" "F.Paste")
			(net "BMC_I2C7_B_DPB_SDA")
			(options
				(clearance outline)
				(anchor circle)
			)
			(primitives
				(gr_poly
					(pts
						(arc
							(start -0.1778 -0.2794)
							(mid -0.249642 -0.249642)
							(end -0.2794 -0.1778)
						)
						(arc
							(start -0.2794 0.1778)
							(mid -0.249642 0.249642)
							(end -0.1778 0.2794)
						)
						(arc
							(start 0.1778 0.2794)
							(mid 0.249642 0.249642)
							(end 0.2794 0.1778)
						)
						(arc
							(start 0.2794 -0.1778)
							(mid 0.249642 -0.249642)
							(end 0.1778 -0.2794)
						)
					)
					(width 0)
					(fill yes)
				)
			)
		)
		(pad "2" smd custom
			(at 0 0.4445 90)
			(size 0.1397 0.1397)
			(layers "F.Cu" "F.Mask" "F.Paste")
			(net "P3V3_STBY")
			(options
				(clearance outline)
				(anchor circle)
			)
			(primitives
				(gr_poly
					(pts
						(arc
							(start -0.1778 -0.2794)
							(mid -0.249642 -0.249642)
							(end -0.2794 -0.1778)
						)
						(arc
							(start -0.2794 0.1778)
							(mid -0.249642 0.249642)
							(end -0.1778 0.2794)
						)
						(arc
							(start 0.1778 0.2794)
							(mid 0.249642 0.249642)
							(end 0.2794 0.1778)
						)
						(arc
							(start 0.2794 -0.1778)
							(mid 0.249642 -0.249642)
							(end 0.1778 -0.2794)
						)
					)
					(width 0)
					(fill yes)
				)
			)
		)
	)
	(footprint ""
		(layer "F.Cu")
		(at 124.944124 -208.889092)
		(property "Reference" "R7916"
			(at 0 0 0)
			(layer "F.SilkS")
			(hide yes)
			(effects
				(font
					(size 1.27 1.27)
				)
			)
		)
		(property "Value" "0R2J-2-GP"
			(at 0.064008 -3.993896 0)
			(unlocked yes)
			(layer "F.Fab")
			(hide yes)
			(effects
				(font
					(size 1.016 1.016)
					(thickness 0.1524)
				)
			)
		)
		(property "Device Type" "R402H16"
			(at 0.064008 -5.517896 0)
			(unlocked yes)
			(layer "F.Fab")
			(hide yes)
			(effects
				(font
					(size 1.016 1.016)
					(thickness 0.1524)
				)
			)
		)
		(duplicate_pad_numbers_are_jumpers no)
		(fp_line
			(start -0.508 -0.9398)
			(end -0.508 0.9398)
			(stroke
				(width 0.1524)
				(type default)
			)
			(layer "F.SilkS")
		)
		(fp_line
			(start 0.508 -0.9398)
			(end -0.508 -0.9398)
			(stroke
				(width 0.1524)
				(type default)
			)
			(layer "F.SilkS")
		)
		(fp_rect
			(start -0.508 0.9398)
			(end 0.508 -0.9398)
			(stroke
				(width 0)
				(type default)
			)
			(fill no)
			(layer "F.CrtYd")
		)
		(fp_rect
			(start -0.508 0.9398)
			(end 0.508 -0.9398)
			(stroke
				(width 0)
				(type default)
			)
			(fill no)
			(layer "F.Fab")
		)
		(pad "1" smd custom
			(at 0 -0.4445)
			(size 0.1397 0.1397)
			(layers "F.Cu" "F.Mask" "F.Paste")
			(net "TWI_SCL1")
			(options
				(clearance outline)
				(anchor circle)
			)
			(primitives
				(gr_poly
					(pts
						(arc
							(start -0.1778 -0.2794)
							(mid -0.249642 -0.249642)
							(end -0.2794 -0.1778)
						)
						(arc
							(start -0.2794 0.1778)
							(mid -0.249642 0.249642)
							(end -0.1778 0.2794)
						)
						(arc
							(start 0.1778 0.2794)
							(mid 0.249642 0.249642)
							(end 0.2794 0.1778)
						)
						(arc
							(start 0.2794 -0.1778)
							(mid 0.249642 -0.249642)
							(end 0.1778 -0.2794)
						)
					)
					(width 0)
					(fill yes)
				)
			)
		)
		(pad "2" smd custom
			(at 0 0.4445)
			(size 0.1397 0.1397)
			(layers "F.Cu" "F.Mask" "F.Paste")
			(net "I2C_GPIO_SCL_2")
			(options
				(clearance outline)
				(anchor circle)
			)
			(primitives
				(gr_poly
					(pts
						(arc
							(start -0.1778 -0.2794)
							(mid -0.249642 -0.249642)
							(end -0.2794 -0.1778)
						)
						(arc
							(start -0.2794 0.1778)
							(mid -0.249642 0.249642)
							(end -0.1778 0.2794)
						)
						(arc
							(start 0.1778 0.2794)
							(mid 0.249642 0.249642)
							(end 0.2794 0.1778)
						)
						(arc
							(start 0.2794 -0.1778)
							(mid 0.249642 -0.249642)
							(end 0.1778 -0.2794)
						)
					)
					(width 0)
					(fill yes)
				)
			)
		)
	)
	(footprint ""
		(layer "F.Cu")
		(at 21.0566 -190.3222 90)
		(property "Reference" "C7276"
			(at 0 0 90)
			(layer "F.SilkS")
			(hide yes)
			(effects
				(font
					(size 1.27 1.27)
				)
			)
		)
		(property "Value" "SC1U16V3KX-5GP"
			(at 0 -2.8194 90)
			(unlocked yes)
			(layer "F.Fab")
			(hide yes)
			(effects
				(font
					(size 1.016 1.016)
					(thickness 0.1524)
				)
			)
		)
		(property "Device Type" "C603H36"
			(at 0 -4.3434 90)
			(unlocked yes)
			(layer "F.Fab")
			(hide yes)
			(effects
				(font
					(size 1.016 1.016)
					(thickness 0.1524)
				)
			)
		)
		(duplicate_pad_numbers_are_jumpers no)
		(fp_line
			(start 0.508 0)
			(end -0.508 0)
			(stroke
				(width 0.2032)
				(type default)
			)
			(layer "F.SilkS")
		)
		(fp_rect
			(start -0.5842 1.3335)
			(end 0.5842 -1.3335)
			(stroke
				(width 0)
				(type default)
			)
			(fill no)
			(layer "F.CrtYd")
		)
		(fp_rect
			(start -0.5842 1.3335)
			(end 0.5842 -1.3335)
			(stroke
				(width 0)
				(type default)
			)
			(fill no)
			(layer "F.Fab")
		)
		(pad "1" smd custom
			(at 0 -0.762 90)
			(size 0.2159 0.2159)
			(layers "F.Cu" "F.Mask" "F.Paste")
			(net "MB0_CM_UV_R")
			(options
				(clearance outline)
				(anchor circle)
			)
			(primitives
				(gr_poly
					(pts
						(arc
							(start -0.3302 -0.4318)
							(mid -0.402042 -0.402042)
							(end -0.4318 -0.3302)
						)
						(arc
							(start -0.4318 0.3302)
							(mid -0.402042 0.402042)
							(end -0.3302 0.4318)
						)
						(arc
							(start 0.3302 0.4318)
							(mid 0.402042 0.402042)
							(end 0.4318 0.3302)
						)
						(arc
							(start 0.4318 -0.3302)
							(mid 0.402042 -0.402042)
							(end 0.3302 -0.4318)
						)
					)
					(width 0)
					(fill yes)
				)
			)
		)
		(pad "2" smd custom
			(at 0 0.762 90)
			(size 0.2159 0.2159)
			(layers "F.Cu" "F.Mask" "F.Paste")
			(net "AGND_CURRENT_MON")
			(options
				(clearance outline)
				(anchor circle)
			)
			(primitives
				(gr_poly
					(pts
						(arc
							(start -0.3302 -0.4318)
							(mid -0.402042 -0.402042)
							(end -0.4318 -0.3302)
						)
						(arc
							(start -0.4318 0.3302)
							(mid -0.402042 0.402042)
							(end -0.3302 0.4318)
						)
						(arc
							(start 0.3302 0.4318)
							(mid 0.402042 0.402042)
							(end 0.4318 0.3302)
						)
						(arc
							(start 0.4318 -0.3302)
							(mid 0.402042 -0.402042)
							(end 0.3302 -0.4318)
						)
					)
					(width 0)
					(fill yes)
				)
			)
		)
	)
	(footprint ""
		(layer "F.Cu")
		(at 167.767 -94.5134 90)
		(property "Reference" "TP74"
			(at 0 0 90)
			(layer "F.SilkS")
			(hide yes)
			(effects
				(font
					(size 1.27 1.27)
				)
			)
		)
		(property "Value" "TPAD28-2-GP"
			(at -0.0127 -1.6637 90)
			(unlocked yes)
			(layer "F.Fab")
			(hide yes)
			(effects
				(font
					(size 1.016 1.016)
					(thickness 0.1524)
				)
			)
		)
		(property "Device Type" "TPAD28"
			(at -0.0127 -3.1877 90)
			(unlocked yes)
			(layer "F.Fab")
			(hide yes)
			(effects
				(font
					(size 1.016 1.016)
					(thickness 0.1524)
				)
			)
		)
		(duplicate_pad_numbers_are_jumpers no)
		(fp_poly
			(pts
				(arc
					(start 0 0.3556)
					(mid 0 -0.3556)
					(end 0 0.3556)
				)
			)
			(stroke
				(width 0)
				(type default)
			)
			(fill no)
			(layer "F.CrtYd")
		)
		(fp_poly
			(pts
				(arc
					(start 0 0.6096)
					(mid 0 -0.6096)
					(end 0 0.6096)
				)
			)
			(stroke
				(width 0)
				(type default)
			)
			(fill no)
			(layer "F.Fab")
		)
		(pad "1" smd circle
			(at 0 0 90)
			(size 0.7112 0.7112)
			(layers "F.Cu" "F.Mask" "F.Paste")
			(net "CLKGEN_OE2")
		)
	)
)
